(kicad_pcb
	(version 20260206)
	(generator "pcbnew")
	(generator_version "10.0")
	(general
		(thickness 1.6)
		(legacy_teardrops no)
	)
	(paper "A4")
	(title_block
		(title "Wiwynn_Tioga_Pass_MB.brd")
		(comment 1 "Tioga Pass / footprints 4358-4364 of 4770")
	)
	(layers
		(0 "F.Cu" signal "TOP")
		(4 "In1.Cu" signal "L2GND")
		(6 "In2.Cu" signal "L3")
		(8 "In3.Cu" signal "L4GND")
		(10 "In4.Cu" signal "L5")
		(12 "In5.Cu" signal "L6GND")
		(14 "In6.Cu" signal "L7VCC")
		(16 "In7.Cu" signal "L8VCC")
		(18 "In8.Cu" signal "L9GND")
		(20 "In9.Cu" signal "L10")
		(22 "In10.Cu" signal "L11GND")
		(24 "In11.Cu" signal "L12")
		(26 "In12.Cu" signal "L13GND")
		(2 "B.Cu" signal "BOTTOM")
		(9 "F.Adhes" user "F.Adhesive")
		(11 "B.Adhes" user "B.Adhesive")
		(13 "F.Paste" user "Package Geometry/Pastemask Top")
		(15 "B.Paste" user "Package Geometry/Pastemask Bottom")
		(5 "F.SilkS" user "Ref Des/Silkscreen Top")
		(7 "B.SilkS" user "Ref Des/Silkscreen Bottom")
		(1 "F.Mask" user "Board Geometry/Soldermask Top")
		(3 "B.Mask" user "Board Geometry/Soldermask Bottom")
		(17 "Dwgs.User" user "User.Drawings")
		(19 "Cmts.User" user "User.Comments")
		(21 "Eco1.User" user "User.Eco1")
		(23 "Eco2.User" user "User.Eco2")
		(25 "Edge.Cuts" user "Board Geometry/Outline")
		(27 "Margin" user)
		(31 "F.CrtYd" user "Package Geometry/Place Bound Top")
		(29 "B.CrtYd" user "Package Geometry/Place Bound Bottom")
		(35 "F.Fab" user "Ref Des/Assembly Top")
		(33 "B.Fab" user "Ref Des/Assembly Bottom")
	)
	(footprint ""
		(layer "B.Cu")
		(at 353.6315 -74.549 -90)
		(property "Reference" "R3P35"
			(at 0 0 90)
			(layer "B.SilkS")
			(hide yes)
			(effects
				(font
					(size 1.27 1.27)
				)
				(justify mirror)
			)
		)
		(property "Value" ""
			(at 0 0 90)
			(layer "B.Fab")
			(effects
				(font
					(size 1.27 1.27)
				)
				(justify mirror)
			)
		)
		(duplicate_pad_numbers_are_jumpers no)
		(fp_poly
			(pts
				(xy 0.2794 -0.1016) (xy -0.2794 -0.1016) (xy -0.2794 0.9906) (xy 0.2794 0.9906)
			)
			(stroke
				(width 0)
				(type default)
			)
			(fill no)
			(layer "B.CrtYd")
		)
		(fp_line
			(start -0.2794 0.9906)
			(end -0.2794 -0.1016)
			(stroke
				(width 0.1)
				(type default)
			)
			(layer "B.Fab")
		)
		(fp_line
			(start 0.2794 0.9906)
			(end -0.2794 0.9906)
			(stroke
				(width 0.1)
				(type default)
			)
			(layer "B.Fab")
		)
		(fp_line
			(start -0.2794 -0.1016)
			(end 0.2794 -0.1016)
			(stroke
				(width 0.1)
				(type default)
			)
			(layer "B.Fab")
		)
		(fp_line
			(start 0.2794 -0.1016)
			(end 0.2794 0.9906)
			(stroke
				(width 0.1)
				(type default)
			)
			(layer "B.Fab")
		)
		(pad "1" smd rect
			(at 0 0 90)
			(size 0.508 0.508)
			(layers "B.Cu" "B.Mask" "B.Paste")
			(net "RST_CPU1_LVC3_R1_N")
		)
		(pad "2" smd rect
			(at 0 0.889 90)
			(size 0.508 0.508)
			(layers "B.Cu" "B.Mask" "B.Paste")
			(net "RST_CPU1_LVC3_N")
		)
		(zone
			(layer "B.Cu")
			(hatch none 0.5)
			(connect_pads
				(clearance 0)
			)
			(min_thickness 0.25)
			(keepout
				(tracks not_allowed)
				(vias allowed)
				(pads allowed)
				(copperpour not_allowed)
				(footprints allowed)
			)
			(placement
				(enabled no)
				(sheetname "")
			)
			(fill
				(thermal_gap 0.5)
				(thermal_bridge_width 0.5)
				(island_removal_mode 0)
			)
			(polygon
				(pts
					(xy 352.9965 -74.295) (xy 352.9965 -74.803) (xy 353.3775 -74.803) (xy 353.3775 -74.295)
				)
			)
		)
		(zone
			(layer "B.Cu")
			(hatch none 0.5)
			(connect_pads
				(clearance 0)
			)
			(min_thickness 0.25)
			(keepout
				(tracks allowed)
				(vias not_allowed)
				(pads allowed)
				(copperpour not_allowed)
				(footprints allowed)
			)
			(placement
				(enabled no)
				(sheetname "")
			)
			(fill
				(thermal_gap 0.5)
				(thermal_bridge_width 0.5)
				(island_removal_mode 0)
			)
			(polygon
				(pts
					(xy 353.3775 -74.295) (xy 353.3775 -74.803) (xy 352.9965 -74.803) (xy 352.9965 -74.295)
				)
			)
		)
	)
	(footprint ""
		(layer "B.Cu")
		(at 449.199 -131.318 -90)
		(property "Reference" "R1M20"
			(at 0 0 90)
			(layer "B.SilkS")
			(hide yes)
			(effects
				(font
					(size 1.27 1.27)
				)
				(justify mirror)
			)
		)
		(property "Value" ""
			(at 0 0 90)
			(layer "B.Fab")
			(effects
				(font
					(size 1.27 1.27)
				)
				(justify mirror)
			)
		)
		(duplicate_pad_numbers_are_jumpers no)
		(fp_poly
			(pts
				(xy 0.2794 -0.1016) (xy -0.2794 -0.1016) (xy -0.2794 0.9906) (xy 0.2794 0.9906)
			)
			(stroke
				(width 0)
				(type default)
			)
			(fill no)
			(layer "B.CrtYd")
		)
		(fp_line
			(start -0.2794 0.9906)
			(end -0.2794 -0.1016)
			(stroke
				(width 0.1)
				(type default)
			)
			(layer "B.Fab")
		)
		(fp_line
			(start 0.2794 0.9906)
			(end -0.2794 0.9906)
			(stroke
				(width 0.1)
				(type default)
			)
			(layer "B.Fab")
		)
		(fp_line
			(start -0.2794 -0.1016)
			(end 0.2794 -0.1016)
			(stroke
				(width 0.1)
				(type default)
			)
			(layer "B.Fab")
		)
		(fp_line
			(start 0.2794 -0.1016)
			(end 0.2794 0.9906)
			(stroke
				(width 0.1)
				(type default)
			)
			(layer "B.Fab")
		)
		(pad "1" smd rect
			(at 0 0 90)
			(size 0.508 0.508)
			(layers "B.Cu" "B.Mask" "B.Paste")
			(net "P1V8_MCP_CPU0")
		)
		(pad "2" smd rect
			(at 0 0.889 90)
			(size 0.508 0.508)
			(layers "B.Cu" "B.Mask" "B.Paste")
			(net "JTAG_MCP_MUX_TDI")
		)
		(zone
			(layer "B.Cu")
			(hatch none 0.5)
			(connect_pads
				(clearance 0)
			)
			(min_thickness 0.25)
			(keepout
				(tracks not_allowed)
				(vias allowed)
				(pads allowed)
				(copperpour not_allowed)
				(footprints allowed)
			)
			(placement
				(enabled no)
				(sheetname "")
			)
			(fill
				(thermal_gap 0.5)
				(thermal_bridge_width 0.5)
				(island_removal_mode 0)
			)
			(polygon
				(pts
					(xy 448.564 -131.064) (xy 448.564 -131.572) (xy 448.945 -131.572) (xy 448.945 -131.064)
				)
			)
		)
		(zone
			(layer "B.Cu")
			(hatch none 0.5)
			(connect_pads
				(clearance 0)
			)
			(min_thickness 0.25)
			(keepout
				(tracks allowed)
				(vias not_allowed)
				(pads allowed)
				(copperpour not_allowed)
				(footprints allowed)
			)
			(placement
				(enabled no)
				(sheetname "")
			)
			(fill
				(thermal_gap 0.5)
				(thermal_bridge_width 0.5)
				(island_removal_mode 0)
			)
			(polygon
				(pts
					(xy 448.945 -131.064) (xy 448.945 -131.572) (xy 448.564 -131.572) (xy 448.564 -131.064)
				)
			)
		)
	)
	(footprint ""
		(layer "B.Cu")
		(at 357.378 -33.782)
		(property "Reference" "C3T6"
			(at 3.27533 3.048 270)
			(unlocked yes)
			(layer "B.SilkS")
			(effects
				(font
					(size 0.7874 0.5842)
					(thickness 0.1524)
				)
				(justify mirror)
			)
		)
		(property "Value" ""
			(at 0 0 0)
			(layer "B.Fab")
			(effects
				(font
					(size 1.27 1.27)
				)
				(justify mirror)
			)
		)
		(duplicate_pad_numbers_are_jumpers no)
		(fp_line
			(start -2.504948 -1.616456)
			(end -2.504948 1.633728)
			(stroke
				(width 0.1524)
				(type default)
			)
			(layer "B.SilkS")
		)
		(fp_line
			(start -2.504948 1.633728)
			(end -1.6002 1.633728)
			(stroke
				(width 0.1524)
				(type default)
			)
			(layer "B.SilkS")
		)
		(fp_line
			(start -2.286 7.366)
			(end -2.286 1.63195)
			(stroke
				(width 0.1524)
				(type default)
			)
			(layer "B.SilkS")
		)
		(fp_line
			(start -2.286 7.366)
			(end -1.600708 7.366)
			(stroke
				(width 0.1524)
				(type default)
			)
			(layer "B.SilkS")
		)
		(fp_line
			(start -1.6002 -1.616456)
			(end -2.504948 -1.616456)
			(stroke
				(width 0.1524)
				(type default)
			)
			(layer "B.SilkS")
		)
		(fp_line
			(start 1.6002 -1.616456)
			(end 2.563114 -1.616456)
			(stroke
				(width 0.1524)
				(type default)
			)
			(layer "B.SilkS")
		)
		(fp_line
			(start 2.286 7.366)
			(end 1.60147 7.366)
			(stroke
				(width 0.1524)
				(type default)
			)
			(layer "B.SilkS")
		)
		(fp_line
			(start 2.286 7.366)
			(end 2.286 1.632712)
			(stroke
				(width 0.1524)
				(type default)
			)
			(layer "B.SilkS")
		)
		(fp_line
			(start 2.563114 -1.616456)
			(end 2.563114 1.633728)
			(stroke
				(width 0.1524)
				(type default)
			)
			(layer "B.SilkS")
		)
		(fp_line
			(start 2.563114 1.633728)
			(end 1.6002 1.633728)
			(stroke
				(width 0.1524)
				(type default)
			)
			(layer "B.SilkS")
		)
		(fp_rect
			(start 2.286 7.366)
			(end -2.286 -0.254)
			(stroke
				(width 0)
				(type default)
			)
			(fill no)
			(layer "B.CrtYd")
		)
		(fp_line
			(start -2.286 -0.254)
			(end -2.286 7.366)
			(stroke
				(width 0.1)
				(type default)
			)
			(layer "B.Fab")
		)
		(fp_line
			(start -2.286 7.366)
			(end 2.286 7.366)
			(stroke
				(width 0.1)
				(type default)
			)
			(layer "B.Fab")
		)
		(fp_line
			(start 2.286 -0.254)
			(end -2.286 -0.254)
			(stroke
				(width 0.1)
				(type default)
			)
			(layer "B.Fab")
		)
		(fp_line
			(start 2.286 7.366)
			(end 2.286 -0.254)
			(stroke
				(width 0.1)
				(type default)
			)
			(layer "B.Fab")
		)
		(pad "1" smd rect
			(at 0 0 180)
			(size 2.54 3.048)
			(layers "B.Cu" "B.Mask" "B.Paste")
			(net "P12V_STBY")
		)
		(pad "2" smd rect
			(at 0 7.112 180)
			(size 2.54 3.048)
			(layers "B.Cu" "B.Mask" "B.Paste")
			(net "GND")
		)
	)
	(footprint ""
		(layer "B.Cu")
		(at 459.359 -153.924 90)
		(property "Reference" "C1L1"
			(at 0 0 90)
			(layer "B.SilkS")
			(hide yes)
			(effects
				(font
					(size 1.27 1.27)
				)
				(justify mirror)
			)
		)
		(property "Value" ""
			(at 0 0 90)
			(layer "B.Fab")
			(effects
				(font
					(size 1.27 1.27)
				)
				(justify mirror)
			)
		)
		(duplicate_pad_numbers_are_jumpers no)
		(fp_poly
			(pts
				(xy -0.3048 -0.1016) (xy -0.3048 0.9906) (xy 0.3048 0.9906) (xy 0.3048 -0.1016)
			)
			(stroke
				(width 0)
				(type default)
			)
			(fill no)
			(layer "B.CrtYd")
		)
		(fp_line
			(start 0.3048 -0.1016)
			(end 0.3048 0.9906)
			(stroke
				(width 0.1)
				(type default)
			)
			(layer "B.Fab")
		)
		(fp_line
			(start -0.3048 -0.1016)
			(end 0.3048 -0.1016)
			(stroke
				(width 0.1)
				(type default)
			)
			(layer "B.Fab")
		)
		(fp_line
			(start 0.3048 0.9906)
			(end -0.3048 0.9906)
			(stroke
				(width 0.1)
				(type default)
			)
			(layer "B.Fab")
		)
		(fp_line
			(start -0.3048 0.9906)
			(end -0.3048 -0.1016)
			(stroke
				(width 0.1)
				(type default)
			)
			(layer "B.Fab")
		)
		(pad "1" smd rect
			(at 0 0 270)
			(size 0.508 0.508)
			(layers "B.Cu" "B.Mask" "B.Paste")
			(net "P3V3_STBY")
		)
		(pad "2" smd rect
			(at 0 0.889 270)
			(size 0.508 0.508)
			(layers "B.Cu" "B.Mask" "B.Paste")
			(net "GND")
		)
		(zone
			(layer "B.Cu")
			(hatch none 0.5)
			(connect_pads
				(clearance 0)
			)
			(min_thickness 0.25)
			(keepout
				(tracks allowed)
				(vias not_allowed)
				(pads allowed)
				(copperpour not_allowed)
				(footprints allowed)
			)
			(placement
				(enabled no)
				(sheetname "")
			)
			(fill
				(thermal_gap 0.5)
				(thermal_bridge_width 0.5)
				(island_removal_mode 0)
			)
			(polygon
				(pts
					(xy 459.613 -154.178) (xy 459.613 -153.67) (xy 459.994 -153.67) (xy 459.994 -154.178)
				)
			)
		)
		(zone
			(layer "B.Cu")
			(hatch none 0.5)
			(connect_pads
				(clearance 0)
			)
			(min_thickness 0.25)
			(keepout
				(tracks not_allowed)
				(vias allowed)
				(pads allowed)
				(copperpour not_allowed)
				(footprints allowed)
			)
			(placement
				(enabled no)
				(sheetname "")
			)
			(fill
				(thermal_gap 0.5)
				(thermal_bridge_width 0.5)
				(island_removal_mode 0)
			)
			(polygon
				(pts
					(xy 459.994 -154.178) (xy 459.994 -153.67) (xy 459.613 -153.67) (xy 459.613 -154.178)
				)
			)
		)
	)
	(footprint ""
		(layer "B.Cu")
		(at 401.20316 -54.25186)
		(property "Reference" "C3T5"
			(at 0 0 0)
			(layer "B.SilkS")
			(hide yes)
			(effects
				(font
					(size 1.27 1.27)
				)
				(justify mirror)
			)
		)
		(property "Value" ""
			(at 0 0 0)
			(layer "B.Fab")
			(effects
				(font
					(size 1.27 1.27)
				)
				(justify mirror)
			)
		)
		(duplicate_pad_numbers_are_jumpers no)
		(fp_poly
			(pts
				(xy -0.3048 -0.1016) (xy -0.3048 0.9906) (xy 0.3048 0.9906) (xy 0.3048 -0.1016)
			)
			(stroke
				(width 0)
				(type default)
			)
			(fill no)
			(layer "B.CrtYd")
		)
		(fp_line
			(start -0.3048 -0.1016)
			(end 0.3048 -0.1016)
			(stroke
				(width 0.1)
				(type default)
			)
			(layer "B.Fab")
		)
		(fp_line
			(start -0.3048 0.9906)
			(end -0.3048 -0.1016)
			(stroke
				(width 0.1)
				(type default)
			)
			(layer "B.Fab")
		)
		(fp_line
			(start 0.3048 -0.1016)
			(end 0.3048 0.9906)
			(stroke
				(width 0.1)
				(type default)
			)
			(layer "B.Fab")
		)
		(fp_line
			(start 0.3048 0.9906)
			(end -0.3048 0.9906)
			(stroke
				(width 0.1)
				(type default)
			)
			(layer "B.Fab")
		)
		(pad "1" smd rect
			(at 0 0 180)
			(size 0.508 0.508)
			(layers "B.Cu" "B.Mask" "B.Paste")
			(net "P3V3_STBY")
		)
		(pad "2" smd rect
			(at 0 0.889 180)
			(size 0.508 0.508)
			(layers "B.Cu" "B.Mask" "B.Paste")
			(net "GND")
		)
		(zone
			(layer "B.Cu")
			(hatch none 0.5)
			(connect_pads
				(clearance 0)
			)
			(min_thickness 0.25)
			(keepout
				(tracks allowed)
				(vias not_allowed)
				(pads allowed)
				(copperpour not_allowed)
				(footprints allowed)
			)
			(placement
				(enabled no)
				(sheetname "")
			)
			(fill
				(thermal_gap 0.5)
				(thermal_bridge_width 0.5)
				(island_removal_mode 0)
			)
			(polygon
				(pts
					(xy 401.45716 -53.99786) (xy 400.94916 -53.99786) (xy 400.94916 -53.61686) (xy 401.45716 -53.61686)
				)
			)
		)
		(zone
			(layer "B.Cu")
			(hatch none 0.5)
			(connect_pads
				(clearance 0)
			)
			(min_thickness 0.25)
			(keepout
				(tracks not_allowed)
				(vias allowed)
				(pads allowed)
				(copperpour not_allowed)
				(footprints allowed)
			)
			(placement
				(enabled no)
				(sheetname "")
			)
			(fill
				(thermal_gap 0.5)
				(thermal_bridge_width 0.5)
				(island_removal_mode 0)
			)
			(polygon
				(pts
					(xy 401.45716 -53.61686) (xy 400.94916 -53.61686) (xy 400.94916 -53.99786) (xy 401.45716 -53.99786)
				)
			)
		)
	)
	(footprint ""
		(layer "B.Cu")
		(at 427.795944 -11.947906 -90)
		(property "Reference" "R1U46"
			(at 0 0 90)
			(layer "B.SilkS")
			(hide yes)
			(effects
				(font
					(size 1.27 1.27)
				)
				(justify mirror)
			)
		)
		(property "Value" ""
			(at 0 0 90)
			(layer "B.Fab")
			(effects
				(font
					(size 1.27 1.27)
				)
				(justify mirror)
			)
		)
		(duplicate_pad_numbers_are_jumpers no)
		(fp_poly
			(pts
				(xy 0.2794 -0.1016) (xy -0.2794 -0.1016) (xy -0.2794 0.9906) (xy 0.2794 0.9906)
			)
			(stroke
				(width 0)
				(type default)
			)
			(fill no)
			(layer "B.CrtYd")
		)
		(fp_line
			(start -0.2794 0.9906)
			(end -0.2794 -0.1016)
			(stroke
				(width 0.1)
				(type default)
			)
			(layer "B.Fab")
		)
		(fp_line
			(start 0.2794 0.9906)
			(end -0.2794 0.9906)
			(stroke
				(width 0.1)
				(type default)
			)
			(layer "B.Fab")
		)
		(fp_line
			(start -0.2794 -0.1016)
			(end 0.2794 -0.1016)
			(stroke
				(width 0.1)
				(type default)
			)
			(layer "B.Fab")
		)
		(fp_line
			(start 0.2794 -0.1016)
			(end 0.2794 0.9906)
			(stroke
				(width 0.1)
				(type default)
			)
			(layer "B.Fab")
		)
		(pad "1" smd rect
			(at 0 0 90)
			(size 0.508 0.508)
			(layers "B.Cu" "B.Mask" "B.Paste")
			(net "H_CPU0_MEMABC_MEMHOT_LVT3_K_N")
		)
		(pad "2" smd rect
			(at 0 0.889 90)
			(size 0.508 0.508)
			(layers "B.Cu" "B.Mask" "B.Paste")
			(net "H_CPU0_MEMABC_MEMHOT_LVT3_N")
		)
		(zone
			(layer "B.Cu")
			(hatch none 0.5)
			(connect_pads
				(clearance 0)
			)
			(min_thickness 0.25)
			(keepout
				(tracks not_allowed)
				(vias allowed)
				(pads allowed)
				(copperpour not_allowed)
				(footprints allowed)
			)
			(placement
				(enabled no)
				(sheetname "")
			)
			(fill
				(thermal_gap 0.5)
				(thermal_bridge_width 0.5)
				(island_removal_mode 0)
			)
			(polygon
				(pts
					(xy 427.160944 -11.693906) (xy 427.160944 -12.201906) (xy 427.541944 -12.201906) (xy 427.541944 -11.693906)
				)
			)
		)
		(zone
			(layer "B.Cu")
			(hatch none 0.5)
			(connect_pads
				(clearance 0)
			)
			(min_thickness 0.25)
			(keepout
				(tracks allowed)
				(vias not_allowed)
				(pads allowed)
				(copperpour not_allowed)
				(footprints allowed)
			)
			(placement
				(enabled no)
				(sheetname "")
			)
			(fill
				(thermal_gap 0.5)
				(thermal_bridge_width 0.5)
				(island_removal_mode 0)
			)
			(polygon
				(pts
					(xy 427.541944 -11.693906) (xy 427.541944 -12.201906) (xy 427.160944 -12.201906) (xy 427.160944 -11.693906)
				)
			)
		)
	)
	(footprint ""
		(layer "B.Cu")
		(at 311.15 -123.8504)
		(property "Reference" ""
			(at 0 0 0)
			(layer "B.SilkS")
			(hide yes)
			(effects
				(font
					(size 1.27 1.27)
				)
				(justify mirror)
			)
		)
		(property "Value" ""
			(at 0 0 0)
			(layer "B.Fab")
			(effects
				(font
					(size 1.27 1.27)
				)
				(justify mirror)
			)
		)
		(duplicate_pad_numbers_are_jumpers no)
		(fp_poly
			(pts
				(arc
					(start 2.032 0)
					(mid -2.032 0)
					(end 2.032 0)
				)
			)
			(stroke
				(width 0)
				(type default)
			)
			(fill no)
			(layer "B.CrtYd")
		)
		(pad "1" smd circle
			(at 0 0 180)
			(size 1.016 1.016)
			(layers "B.Cu" "B.Mask" "B.Paste")
			(net "Net_397")
		)
		(zone
			(layers "F.Cu" "B.Cu" "In1.Cu" "In2.Cu" "In3.Cu" "In4.Cu" "In5.Cu" "In6.Cu"
				"In7.Cu" "In8.Cu" "In9.Cu" "In10.Cu" "In11.Cu" "In12.Cu"
			)
			(hatch none 0.5)
			(connect_pads
				(clearance 0)
			)
			(min_thickness 0.25)
			(keepout
				(tracks allowed)
				(vias not_allowed)
				(pads allowed)
				(copperpour not_allowed)
				(footprints allowed)
			)
			(placement
				(enabled no)
				(sheetname "")
			)
			(fill
				(thermal_gap 0.5)
				(thermal_bridge_width 0.5)
				(island_removal_mode 0)
			)
			(polygon
				(pts
					(arc
						(start 312.674 -123.8504)
						(mid 309.626 -123.8504)
						(end 312.674 -123.8504)
					)
				)
			)
		)
		(zone
			(layer "B.Cu")
			(hatch none 0.5)
			(connect_pads
				(clearance 0)
			)
			(min_thickness 0.25)
			(keepout
				(tracks not_allowed)
				(vias allowed)
				(pads allowed)
				(copperpour not_allowed)
				(footprints allowed)
			)
			(placement
				(enabled no)
				(sheetname "")
			)
			(fill
				(thermal_gap 0.5)
				(thermal_bridge_width 0.5)
				(island_removal_mode 0)
			)
			(polygon
				(pts
					(arc
						(start 312.674 -123.8504)
						(mid 309.626 -123.8504)
						(end 312.674 -123.8504)
					)
				)
			)
		)
	)
)
